# S9S_MB_2U (Grand Teton) — schematic netlist excerpt (pin names and nets, part order shuffled) for the footprints in the layout excerpt that follows; sources: Cadence DE-HDL packaged netlist, KiCad conversion of 03242023_DA0F0TMBIJ0_F0T_Motherboard_J_brd_V01_OCP.brd

R4179  Q_RES  33.2 1% CHIP  pkg 0402LF  page 170 : A = SMB_LM75_1_3V3AUX_SCL ; B = SMB_LM75_1_3V3AUX_SCL_R1
R4625  Q_RES  100 1% CHIP  pkg 0402LF  page 213 : A = JTAG_BMC_SW_OE ; B = JTAG_BMC_SW_PLD_OE

(kicad_pcb
	(version 20260206)
	(generator "pcbnew")
	(generator_version "10.0")
	(general
		(thickness 1.6)
		(legacy_teardrops no)
	)
	(paper "A4")
	(title_block
		(title "03242023_DA0F0TMBIJ0_F0T_Motherboard_J_brd_V01_OCP.brd")
		(comment 1 "Grand Teton / footprints 3901-3902 of 6105")
	)
	(layers
		(0 "F.Cu" signal "TOP")
		(4 "In1.Cu" signal "GND")
		(6 "In2.Cu" signal "IN1")
		(8 "In3.Cu" signal "GND1")
		(10 "In4.Cu" signal "IN2")
		(12 "In5.Cu" signal "GND2")
		(14 "In6.Cu" signal "IN3")
		(16 "In7.Cu" signal "GND3")
		(18 "In8.Cu" signal "VCC")
		(20 "In9.Cu" signal "VCC1")
		(22 "In10.Cu" signal "GND4")
		(24 "In11.Cu" signal "IN4")
		(26 "In12.Cu" signal "GND5")
		(28 "In13.Cu" signal "IN5")
		(30 "In14.Cu" signal "GND6")
		(32 "In15.Cu" signal "IN6")
		(34 "In16.Cu" signal "GND7")
		(2 "B.Cu" signal "BOTTOM")
		(9 "F.Adhes" user "F.Adhesive")
		(11 "B.Adhes" user "B.Adhesive")
		(13 "F.Paste" user "Package Geometry/Pastemask Top")
		(15 "B.Paste" user "Package Geometry/Pastemask Bottom")
		(5 "F.SilkS" user "Ref Des/Silkscreen Top")
		(7 "B.SilkS" user "Ref Des/Silkscreen Bottom")
		(1 "F.Mask" user "Board Geometry/Soldermask Top")
		(3 "B.Mask" user "Board Geometry/Soldermask Bottom")
		(17 "Dwgs.User" user "User.Drawings")
		(19 "Cmts.User" user "User.Comments")
		(21 "Eco1.User" user "User.Eco1")
		(23 "Eco2.User" user "User.Eco2")
		(25 "Edge.Cuts" user "Board Geometry/Outline")
		(27 "Margin" user)
		(31 "F.CrtYd" user "Package Geometry/Place Bound Top")
		(29 "B.CrtYd" user "Package Geometry/Place Bound Bottom")
		(35 "F.Fab" user "Ref Des/Assembly Top")
		(33 "B.Fab" user "Ref Des/Assembly Bottom")
	)
	(footprint ""
		(layer "F.Cu")
		(at 285.268162 -15.37843)
		(property "Reference" "R4179"
			(at 0 0 0)
			(layer "F.SilkS")
			(hide yes)
			(effects
				(font
					(size 1.27 1.27)
				)
			)
		)
		(property "Value" ""
			(at 0 0 0)
			(layer "F.Fab")
			(effects
				(font
					(size 1.27 1.27)
				)
			)
		)
		(duplicate_pad_numbers_are_jumpers no)
		(fp_line
			(start -0.7874 -0.4064)
			(end 0.7874 -0.4064)
			(stroke
				(width 0.1524)
				(type default)
			)
			(layer "F.SilkS")
		)
		(fp_line
			(start -0.7874 0.4064)
			(end -0.7874 -0.4064)
			(stroke
				(width 0.1524)
				(type default)
			)
			(layer "F.SilkS")
		)
		(fp_line
			(start 0.7874 -0.4064)
			(end 0.7874 0.4064)
			(stroke
				(width 0.1524)
				(type default)
			)
			(layer "F.SilkS")
		)
		(fp_line
			(start 0.7874 0.4064)
			(end -0.7874 0.4064)
			(stroke
				(width 0.1524)
				(type default)
			)
			(layer "F.SilkS")
		)
		(fp_line
			(start -0.67945 -0.305054)
			(end -0.12065 -0.305054)
			(stroke
				(width 0.1)
				(type default)
			)
			(layer "F.Fab")
		)
		(fp_line
			(start -0.67945 0.3048)
			(end -0.67945 -0.305054)
			(stroke
				(width 0.1)
				(type default)
			)
			(layer "F.Fab")
		)
		(fp_line
			(start -0.12065 -0.305054)
			(end -0.12065 -0.2794)
			(stroke
				(width 0.1)
				(type default)
			)
			(layer "F.Fab")
		)
		(fp_line
			(start -0.12065 -0.2794)
			(end 0.12065 -0.2794)
			(stroke
				(width 0.1)
				(type default)
			)
			(layer "F.Fab")
		)
		(fp_line
			(start -0.12065 0.2794)
			(end -0.12065 0.3048)
			(stroke
				(width 0.1)
				(type default)
			)
			(layer "F.Fab")
		)
		(fp_line
			(start -0.12065 0.3048)
			(end -0.67945 0.3048)
			(stroke
				(width 0.1)
				(type default)
			)
			(layer "F.Fab")
		)
		(fp_line
			(start 0.120396 0.2794)
			(end -0.12065 0.2794)
			(stroke
				(width 0.1)
				(type default)
			)
			(layer "F.Fab")
		)
		(fp_line
			(start 0.120396 0.3048)
			(end 0.120396 0.2794)
			(stroke
				(width 0.1)
				(type default)
			)
			(layer "F.Fab")
		)
		(fp_line
			(start 0.12065 -0.3048)
			(end 0.67945 -0.3048)
			(stroke
				(width 0.1)
				(type default)
			)
			(layer "F.Fab")
		)
		(fp_line
			(start 0.12065 -0.2794)
			(end 0.12065 -0.3048)
			(stroke
				(width 0.1)
				(type default)
			)
			(layer "F.Fab")
		)
		(fp_line
			(start 0.67945 -0.3048)
			(end 0.67945 0.3048)
			(stroke
				(width 0.1)
				(type default)
			)
			(layer "F.Fab")
		)
		(fp_line
			(start 0.67945 0.3048)
			(end 0.120396 0.3048)
			(stroke
				(width 0.1)
				(type default)
			)
			(layer "F.Fab")
		)
		(pad "1" smd circle
			(at -0.40005 0)
			(size 0 0)
			(layers "F.Cu" "F.Mask" "F.Paste")
			(net "SMB_LM75_1_3V3AUX_SCL")
		)
		(pad "2" smd circle
			(at 0.40005 0)
			(size 0 0)
			(layers "F.Cu" "F.Mask" "F.Paste")
			(net "SMB_LM75_1_3V3AUX_SCL_R1")
		)
	)
	(footprint ""
		(layer "F.Cu")
		(at 160.8328 -122.596148)
		(property "Reference" "R4625"
			(at 0 0 0)
			(layer "F.SilkS")
			(hide yes)
			(effects
				(font
					(size 1.27 1.27)
				)
			)
		)
		(property "Value" ""
			(at 0 0 0)
			(layer "F.Fab")
			(effects
				(font
					(size 1.27 1.27)
				)
			)
		)
		(duplicate_pad_numbers_are_jumpers no)
		(fp_line
			(start -0.7874 -0.4064)
			(end 0.7874 -0.4064)
			(stroke
				(width 0.1524)
				(type default)
			)
			(layer "F.SilkS")
		)
		(fp_line
			(start -0.7874 0.4064)
			(end -0.7874 -0.4064)
			(stroke
				(width 0.1524)
				(type default)
			)
			(layer "F.SilkS")
		)
		(fp_line
			(start 0.7874 -0.4064)
			(end 0.7874 0.4064)
			(stroke
				(width 0.1524)
				(type default)
			)
			(layer "F.SilkS")
		)
		(fp_line
			(start 0.7874 0.4064)
			(end -0.7874 0.4064)
			(stroke
				(width 0.1524)
				(type default)
			)
			(layer "F.SilkS")
		)
		(fp_line
			(start -0.67945 -0.305054)
			(end -0.12065 -0.305054)
			(stroke
				(width 0.1)
				(type default)
			)
			(layer "F.Fab")
		)
		(fp_line
			(start -0.67945 0.3048)
			(end -0.67945 -0.305054)
			(stroke
				(width 0.1)
				(type default)
			)
			(layer "F.Fab")
		)
		(fp_line
			(start -0.12065 -0.305054)
			(end -0.12065 -0.2794)
			(stroke
				(width 0.1)
				(type default)
			)
			(layer "F.Fab")
		)
		(fp_line
			(start -0.12065 -0.2794)
			(end 0.12065 -0.2794)
			(stroke
				(width 0.1)
				(type default)
			)
			(layer "F.Fab")
		)
		(fp_line
			(start -0.12065 0.2794)
			(end -0.12065 0.3048)
			(stroke
				(width 0.1)
				(type default)
			)
			(layer "F.Fab")
		)
		(fp_line
			(start -0.12065 0.3048)
			(end -0.67945 0.3048)
			(stroke
				(width 0.1)
				(type default)
			)
			(layer "F.Fab")
		)
		(fp_line
			(start 0.120396 0.2794)
			(end -0.12065 0.2794)
			(stroke
				(width 0.1)
				(type default)
			)
			(layer "F.Fab")
		)
		(fp_line
			(start 0.120396 0.3048)
			(end 0.120396 0.2794)
			(stroke
				(width 0.1)
				(type default)
			)
			(layer "F.Fab")
		)
		(fp_line
			(start 0.12065 -0.3048)
			(end 0.67945 -0.3048)
			(stroke
				(width 0.1)
				(type default)
			)
			(layer "F.Fab")
		)
		(fp_line
			(start 0.12065 -0.2794)
			(end 0.12065 -0.3048)
			(stroke
				(width 0.1)
				(type default)
			)
			(layer "F.Fab")
		)
		(fp_line
			(start 0.67945 -0.3048)
			(end 0.67945 0.3048)
			(stroke
				(width 0.1)
				(type default)
			)
			(layer "F.Fab")
		)
		(fp_line
			(start 0.67945 0.3048)
			(end 0.120396 0.3048)
			(stroke
				(width 0.1)
				(type default)
			)
			(layer "F.Fab")
		)
		(pad "1" smd circle
			(at -0.40005 0)
			(size 0 0)
			(layers "F.Cu" "F.Mask" "F.Paste")
			(net "JTAG_BMC_SW_OE")
		)
		(pad "2" smd circle
			(at 0.40005 0)
			(size 0 0)
			(layers "F.Cu" "F.Mask" "F.Paste")
			(net "JTAG_BMC_SW_PLD_OE")
		)
	)
)
